(kicad_pcb
	(version 20260206)
	(generator "pcbnew")
	(generator_version "10.0")
	(general
		(thickness 1.6)
		(legacy_teardrops no)
	)
	(paper "A4")
	(title_block
		(title "Wiwynn_Tioga_Pass_MB.brd")
		(comment 1 "Tioga Pass / footprints 3759-3766 of 4770")
	)
	(layers
		(0 "F.Cu" signal "TOP")
		(4 "In1.Cu" signal "L2GND")
		(6 "In2.Cu" signal "L3")
		(8 "In3.Cu" signal "L4GND")
		(10 "In4.Cu" signal "L5")
		(12 "In5.Cu" signal "L6GND")
		(14 "In6.Cu" signal "L7VCC")
		(16 "In7.Cu" signal "L8VCC")
		(18 "In8.Cu" signal "L9GND")
		(20 "In9.Cu" signal "L10")
		(22 "In10.Cu" signal "L11GND")
		(24 "In11.Cu" signal "L12")
		(26 "In12.Cu" signal "L13GND")
		(2 "B.Cu" signal "BOTTOM")
		(9 "F.Adhes" user "F.Adhesive")
		(11 "B.Adhes" user "B.Adhesive")
		(13 "F.Paste" user "Package Geometry/Pastemask Top")
		(15 "B.Paste" user "Package Geometry/Pastemask Bottom")
		(5 "F.SilkS" user "Ref Des/Silkscreen Top")
		(7 "B.SilkS" user "Ref Des/Silkscreen Bottom")
		(1 "F.Mask" user "Board Geometry/Soldermask Top")
		(3 "B.Mask" user "Board Geometry/Soldermask Bottom")
		(17 "Dwgs.User" user "User.Drawings")
		(19 "Cmts.User" user "User.Comments")
		(21 "Eco1.User" user "User.Eco1")
		(23 "Eco2.User" user "User.Eco2")
		(25 "Edge.Cuts" user "Board Geometry/Outline")
		(27 "Margin" user)
		(31 "F.CrtYd" user "Package Geometry/Place Bound Top")
		(29 "B.CrtYd" user "Package Geometry/Place Bound Bottom")
		(35 "F.Fab" user "Ref Des/Assembly Top")
		(33 "B.Fab" user "Ref Des/Assembly Bottom")
	)
	(footprint ""
		(layer "B.Cu")
		(at 362.270294 -45.671486)
		(property "Reference" "R2T67"
			(at 0 0 0)
			(layer "B.SilkS")
			(hide yes)
			(effects
				(font
					(size 1.27 1.27)
				)
				(justify mirror)
			)
		)
		(property "Value" ""
			(at 0 0 0)
			(layer "B.Fab")
			(effects
				(font
					(size 1.27 1.27)
				)
				(justify mirror)
			)
		)
		(duplicate_pad_numbers_are_jumpers no)
		(fp_poly
			(pts
				(xy 0.2794 -0.1016) (xy -0.2794 -0.1016) (xy -0.2794 0.9906) (xy 0.2794 0.9906)
			)
			(stroke
				(width 0)
				(type default)
			)
			(fill no)
			(layer "B.CrtYd")
		)
		(fp_line
			(start -0.2794 -0.1016)
			(end 0.2794 -0.1016)
			(stroke
				(width 0.1)
				(type default)
			)
			(layer "B.Fab")
		)
		(fp_line
			(start -0.2794 0.9906)
			(end -0.2794 -0.1016)
			(stroke
				(width 0.1)
				(type default)
			)
			(layer "B.Fab")
		)
		(fp_line
			(start 0.2794 -0.1016)
			(end 0.2794 0.9906)
			(stroke
				(width 0.1)
				(type default)
			)
			(layer "B.Fab")
		)
		(fp_line
			(start 0.2794 0.9906)
			(end -0.2794 0.9906)
			(stroke
				(width 0.1)
				(type default)
			)
			(layer "B.Fab")
		)
		(pad "1" smd rect
			(at 0 0 180)
			(size 0.508 0.508)
			(layers "B.Cu" "B.Mask" "B.Paste")
			(net "FM_CPU0_PROCHOT_LVT3_R_N")
		)
		(pad "2" smd rect
			(at 0 0.889 180)
			(size 0.508 0.508)
			(layers "B.Cu" "B.Mask" "B.Paste")
			(net "FM_CPU0_PROCHOT_LVT3_K_N")
		)
		(zone
			(layer "B.Cu")
			(hatch none 0.5)
			(connect_pads
				(clearance 0)
			)
			(min_thickness 0.25)
			(keepout
				(tracks allowed)
				(vias not_allowed)
				(pads allowed)
				(copperpour not_allowed)
				(footprints allowed)
			)
			(placement
				(enabled no)
				(sheetname "")
			)
			(fill
				(thermal_gap 0.5)
				(thermal_bridge_width 0.5)
				(island_removal_mode 0)
			)
			(polygon
				(pts
					(xy 362.524294 -45.417486) (xy 362.016294 -45.417486) (xy 362.016294 -45.036486) (xy 362.524294 -45.036486)
				)
			)
		)
		(zone
			(layer "B.Cu")
			(hatch none 0.5)
			(connect_pads
				(clearance 0)
			)
			(min_thickness 0.25)
			(keepout
				(tracks not_allowed)
				(vias allowed)
				(pads allowed)
				(copperpour not_allowed)
				(footprints allowed)
			)
			(placement
				(enabled no)
				(sheetname "")
			)
			(fill
				(thermal_gap 0.5)
				(thermal_bridge_width 0.5)
				(island_removal_mode 0)
			)
			(polygon
				(pts
					(xy 362.524294 -45.036486) (xy 362.016294 -45.036486) (xy 362.016294 -45.417486) (xy 362.524294 -45.417486)
				)
			)
		)
	)
	(footprint ""
		(layer "B.Cu")
		(at 375.412 -66.04 180)
		(property "Reference" "R2R7"
			(at 0 0 0)
			(layer "B.SilkS")
			(hide yes)
			(effects
				(font
					(size 1.27 1.27)
				)
				(justify mirror)
			)
		)
		(property "Value" ""
			(at 0 0 0)
			(layer "B.Fab")
			(effects
				(font
					(size 1.27 1.27)
				)
				(justify mirror)
			)
		)
		(duplicate_pad_numbers_are_jumpers no)
		(fp_poly
			(pts
				(xy 0.2794 -0.1016) (xy -0.2794 -0.1016) (xy -0.2794 0.9906) (xy 0.2794 0.9906)
			)
			(stroke
				(width 0)
				(type default)
			)
			(fill no)
			(layer "B.CrtYd")
		)
		(fp_line
			(start 0.2794 0.9906)
			(end -0.2794 0.9906)
			(stroke
				(width 0.1)
				(type default)
			)
			(layer "B.Fab")
		)
		(fp_line
			(start 0.2794 -0.1016)
			(end 0.2794 0.9906)
			(stroke
				(width 0.1)
				(type default)
			)
			(layer "B.Fab")
		)
		(fp_line
			(start -0.2794 0.9906)
			(end -0.2794 -0.1016)
			(stroke
				(width 0.1)
				(type default)
			)
			(layer "B.Fab")
		)
		(fp_line
			(start -0.2794 -0.1016)
			(end 0.2794 -0.1016)
			(stroke
				(width 0.1)
				(type default)
			)
			(layer "B.Fab")
		)
		(pad "1" smd rect
			(at 0 0)
			(size 0.508 0.508)
			(layers "B.Cu" "B.Mask" "B.Paste")
			(net "P3V3_STBY")
		)
		(pad "2" smd rect
			(at 0 0.889)
			(size 0.508 0.508)
			(layers "B.Cu" "B.Mask" "B.Paste")
			(net "FM_FORCE_ADR_N")
		)
		(zone
			(layer "B.Cu")
			(hatch none 0.5)
			(connect_pads
				(clearance 0)
			)
			(min_thickness 0.25)
			(keepout
				(tracks not_allowed)
				(vias allowed)
				(pads allowed)
				(copperpour not_allowed)
				(footprints allowed)
			)
			(placement
				(enabled no)
				(sheetname "")
			)
			(fill
				(thermal_gap 0.5)
				(thermal_bridge_width 0.5)
				(island_removal_mode 0)
			)
			(polygon
				(pts
					(xy 375.158 -66.675) (xy 375.666 -66.675) (xy 375.666 -66.294) (xy 375.158 -66.294)
				)
			)
		)
		(zone
			(layer "B.Cu")
			(hatch none 0.5)
			(connect_pads
				(clearance 0)
			)
			(min_thickness 0.25)
			(keepout
				(tracks allowed)
				(vias not_allowed)
				(pads allowed)
				(copperpour not_allowed)
				(footprints allowed)
			)
			(placement
				(enabled no)
				(sheetname "")
			)
			(fill
				(thermal_gap 0.5)
				(thermal_bridge_width 0.5)
				(island_removal_mode 0)
			)
			(polygon
				(pts
					(xy 375.158 -66.294) (xy 375.666 -66.294) (xy 375.666 -66.675) (xy 375.158 -66.675)
				)
			)
		)
	)
	(footprint ""
		(layer "B.Cu")
		(at 485.942894 4.157472 -90)
		(property "Reference" "C9G2"
			(at 0 0 90)
			(layer "B.SilkS")
			(hide yes)
			(effects
				(font
					(size 1.27 1.27)
				)
				(justify mirror)
			)
		)
		(property "Value" ""
			(at 0 0 90)
			(layer "B.Fab")
			(effects
				(font
					(size 1.27 1.27)
				)
				(justify mirror)
			)
		)
		(duplicate_pad_numbers_are_jumpers no)
		(fp_poly
			(pts
				(xy -0.3048 -0.1016) (xy -0.3048 0.9906) (xy 0.3048 0.9906) (xy 0.3048 -0.1016)
			)
			(stroke
				(width 0)
				(type default)
			)
			(fill no)
			(layer "B.CrtYd")
		)
		(fp_line
			(start -0.3048 0.9906)
			(end -0.3048 -0.1016)
			(stroke
				(width 0.1)
				(type default)
			)
			(layer "B.Fab")
		)
		(fp_line
			(start 0.3048 0.9906)
			(end -0.3048 0.9906)
			(stroke
				(width 0.1)
				(type default)
			)
			(layer "B.Fab")
		)
		(fp_line
			(start -0.3048 -0.1016)
			(end 0.3048 -0.1016)
			(stroke
				(width 0.1)
				(type default)
			)
			(layer "B.Fab")
		)
		(fp_line
			(start 0.3048 -0.1016)
			(end 0.3048 0.9906)
			(stroke
				(width 0.1)
				(type default)
			)
			(layer "B.Fab")
		)
		(pad "1" smd rect
			(at 0 0 90)
			(size 0.508 0.508)
			(layers "B.Cu" "B.Mask" "B.Paste")
			(net "P3V3_STBY")
		)
		(pad "2" smd rect
			(at 0 0.889 90)
			(size 0.508 0.508)
			(layers "B.Cu" "B.Mask" "B.Paste")
			(net "GND")
		)
		(zone
			(layer "B.Cu")
			(hatch none 0.5)
			(connect_pads
				(clearance 0)
			)
			(min_thickness 0.25)
			(keepout
				(tracks not_allowed)
				(vias allowed)
				(pads allowed)
				(copperpour not_allowed)
				(footprints allowed)
			)
			(placement
				(enabled no)
				(sheetname "")
			)
			(fill
				(thermal_gap 0.5)
				(thermal_bridge_width 0.5)
				(island_removal_mode 0)
			)
			(polygon
				(pts
					(xy 485.307894 4.411472) (xy 485.307894 3.903472) (xy 485.688894 3.903472) (xy 485.688894 4.411472)
				)
			)
		)
		(zone
			(layer "B.Cu")
			(hatch none 0.5)
			(connect_pads
				(clearance 0)
			)
			(min_thickness 0.25)
			(keepout
				(tracks allowed)
				(vias not_allowed)
				(pads allowed)
				(copperpour not_allowed)
				(footprints allowed)
			)
			(placement
				(enabled no)
				(sheetname "")
			)
			(fill
				(thermal_gap 0.5)
				(thermal_bridge_width 0.5)
				(island_removal_mode 0)
			)
			(polygon
				(pts
					(xy 485.688894 4.411472) (xy 485.688894 3.903472) (xy 485.307894 3.903472) (xy 485.307894 4.411472)
				)
			)
		)
	)
	(footprint ""
		(layer "B.Cu")
		(at 357.133398 -77.915516)
		(property "Reference" "C3P36"
			(at 0 0 0)
			(layer "B.SilkS")
			(hide yes)
			(effects
				(font
					(size 1.27 1.27)
				)
				(justify mirror)
			)
		)
		(property "Value" ""
			(at 0 0 0)
			(layer "B.Fab")
			(effects
				(font
					(size 1.27 1.27)
				)
				(justify mirror)
			)
		)
		(duplicate_pad_numbers_are_jumpers no)
		(fp_poly
			(pts
				(xy -0.3048 -0.1016) (xy -0.3048 0.9906) (xy 0.3048 0.9906) (xy 0.3048 -0.1016)
			)
			(stroke
				(width 0)
				(type default)
			)
			(fill no)
			(layer "B.CrtYd")
		)
		(fp_line
			(start -0.3048 -0.1016)
			(end 0.3048 -0.1016)
			(stroke
				(width 0.1)
				(type default)
			)
			(layer "B.Fab")
		)
		(fp_line
			(start -0.3048 0.9906)
			(end -0.3048 -0.1016)
			(stroke
				(width 0.1)
				(type default)
			)
			(layer "B.Fab")
		)
		(fp_line
			(start 0.3048 -0.1016)
			(end 0.3048 0.9906)
			(stroke
				(width 0.1)
				(type default)
			)
			(layer "B.Fab")
		)
		(fp_line
			(start 0.3048 0.9906)
			(end -0.3048 0.9906)
			(stroke
				(width 0.1)
				(type default)
			)
			(layer "B.Fab")
		)
		(pad "1" smd rect
			(at 0 0 180)
			(size 0.508 0.508)
			(layers "B.Cu" "B.Mask" "B.Paste")
			(net "P3E_CPU0_PE1_SS_TXN<6>")
		)
		(pad "2" smd rect
			(at 0 0.889 180)
			(size 0.508 0.508)
			(layers "B.Cu" "B.Mask" "B.Paste")
			(net "P3E_CPU0_PE1_SS_C_TXN<6>")
		)
		(zone
			(layer "B.Cu")
			(hatch none 0.5)
			(connect_pads
				(clearance 0)
			)
			(min_thickness 0.25)
			(keepout
				(tracks allowed)
				(vias not_allowed)
				(pads allowed)
				(copperpour not_allowed)
				(footprints allowed)
			)
			(placement
				(enabled no)
				(sheetname "")
			)
			(fill
				(thermal_gap 0.5)
				(thermal_bridge_width 0.5)
				(island_removal_mode 0)
			)
			(polygon
				(pts
					(xy 357.387398 -77.661516) (xy 356.879398 -77.661516) (xy 356.879398 -77.280516) (xy 357.387398 -77.280516)
				)
			)
		)
		(zone
			(layer "B.Cu")
			(hatch none 0.5)
			(connect_pads
				(clearance 0)
			)
			(min_thickness 0.25)
			(keepout
				(tracks not_allowed)
				(vias allowed)
				(pads allowed)
				(copperpour not_allowed)
				(footprints allowed)
			)
			(placement
				(enabled no)
				(sheetname "")
			)
			(fill
				(thermal_gap 0.5)
				(thermal_bridge_width 0.5)
				(island_removal_mode 0)
			)
			(polygon
				(pts
					(xy 357.387398 -77.280516) (xy 356.879398 -77.280516) (xy 356.879398 -77.661516) (xy 357.387398 -77.661516)
				)
			)
		)
	)
	(footprint ""
		(layer "B.Cu")
		(at 333.6798 -28.3083 90)
		(property "Reference" "C3T9"
			(at 0 0 90)
			(layer "B.SilkS")
			(hide yes)
			(effects
				(font
					(size 1.27 1.27)
				)
				(justify mirror)
			)
		)
		(property "Value" ""
			(at 0 0 90)
			(layer "B.Fab")
			(effects
				(font
					(size 1.27 1.27)
				)
				(justify mirror)
			)
		)
		(duplicate_pad_numbers_are_jumpers no)
		(fp_rect
			(start -0.7239 -0.2159)
			(end 0.7239 1.9939)
			(stroke
				(width 0)
				(type default)
			)
			(fill no)
			(layer "B.CrtYd")
		)
		(fp_line
			(start 0.7239 -0.2159)
			(end 0.7239 1.9939)
			(stroke
				(width 0.1)
				(type default)
			)
			(layer "B.Fab")
		)
		(fp_line
			(start -0.7239 -0.2159)
			(end 0.7239 -0.2159)
			(stroke
				(width 0.1)
				(type default)
			)
			(layer "B.Fab")
		)
		(fp_line
			(start 0.7239 1.9939)
			(end -0.7239 1.9939)
			(stroke
				(width 0.1)
				(type default)
			)
			(layer "B.Fab")
		)
		(fp_line
			(start -0.7239 1.9939)
			(end -0.7239 -0.2159)
			(stroke
				(width 0.1)
				(type default)
			)
			(layer "B.Fab")
		)
		(pad "1" smd rect
			(at 0 0 270)
			(size 1.27 1.016)
			(layers "B.Cu" "B.Mask" "B.Paste")
			(net "PVPP_ABC")
		)
		(pad "2" smd rect
			(at 0 1.778 270)
			(size 1.27 1.016)
			(layers "B.Cu" "B.Mask" "B.Paste")
			(net "GND")
		)
		(zone
			(layer "B.Cu")
			(hatch none 0.5)
			(connect_pads
				(clearance 0)
			)
			(min_thickness 0.25)
			(keepout
				(tracks not_allowed)
				(vias allowed)
				(pads allowed)
				(copperpour not_allowed)
				(footprints allowed)
			)
			(placement
				(enabled no)
				(sheetname "")
			)
			(fill
				(thermal_gap 0.5)
				(thermal_bridge_width 0.5)
				(island_removal_mode 0)
			)
			(polygon
				(pts
					(xy 334.1878 -27.6733) (xy 334.9498 -27.6733) (xy 334.9498 -28.9433) (xy 334.1878 -28.9433)
				)
			)
		)
	)
	(footprint ""
		(layer "B.Cu")
		(at 496.17376 -124.0663 180)
		(property "Reference" "R1M10"
			(at 0 0 0)
			(layer "B.SilkS")
			(hide yes)
			(effects
				(font
					(size 1.27 1.27)
				)
				(justify mirror)
			)
		)
		(property "Value" ""
			(at 0 0 0)
			(layer "B.Fab")
			(effects
				(font
					(size 1.27 1.27)
				)
				(justify mirror)
			)
		)
		(duplicate_pad_numbers_are_jumpers no)
		(fp_poly
			(pts
				(xy 0.2794 -0.1016) (xy -0.2794 -0.1016) (xy -0.2794 0.9906) (xy 0.2794 0.9906)
			)
			(stroke
				(width 0)
				(type default)
			)
			(fill no)
			(layer "B.CrtYd")
		)
		(fp_line
			(start 0.2794 0.9906)
			(end -0.2794 0.9906)
			(stroke
				(width 0.1)
				(type default)
			)
			(layer "B.Fab")
		)
		(fp_line
			(start 0.2794 -0.1016)
			(end 0.2794 0.9906)
			(stroke
				(width 0.1)
				(type default)
			)
			(layer "B.Fab")
		)
		(fp_line
			(start -0.2794 0.9906)
			(end -0.2794 -0.1016)
			(stroke
				(width 0.1)
				(type default)
			)
			(layer "B.Fab")
		)
		(fp_line
			(start -0.2794 -0.1016)
			(end 0.2794 -0.1016)
			(stroke
				(width 0.1)
				(type default)
			)
			(layer "B.Fab")
		)
		(pad "1" smd rect
			(at 0 0)
			(size 0.508 0.508)
			(layers "B.Cu" "B.Mask" "B.Paste")
			(net "LED_PCH_SATA_HDD_N")
		)
		(pad "2" smd rect
			(at 0 0.889)
			(size 0.508 0.508)
			(layers "B.Cu" "B.Mask" "B.Paste")
			(net "LED_SATA_ACT_R_N")
		)
		(zone
			(layer "B.Cu")
			(hatch none 0.5)
			(connect_pads
				(clearance 0)
			)
			(min_thickness 0.25)
			(keepout
				(tracks not_allowed)
				(vias allowed)
				(pads allowed)
				(copperpour not_allowed)
				(footprints allowed)
			)
			(placement
				(enabled no)
				(sheetname "")
			)
			(fill
				(thermal_gap 0.5)
				(thermal_bridge_width 0.5)
				(island_removal_mode 0)
			)
			(polygon
				(pts
					(xy 495.91976 -124.7013) (xy 496.42776 -124.7013) (xy 496.42776 -124.3203) (xy 495.91976 -124.3203)
				)
			)
		)
		(zone
			(layer "B.Cu")
			(hatch none 0.5)
			(connect_pads
				(clearance 0)
			)
			(min_thickness 0.25)
			(keepout
				(tracks allowed)
				(vias not_allowed)
				(pads allowed)
				(copperpour not_allowed)
				(footprints allowed)
			)
			(placement
				(enabled no)
				(sheetname "")
			)
			(fill
				(thermal_gap 0.5)
				(thermal_bridge_width 0.5)
				(island_removal_mode 0)
			)
			(polygon
				(pts
					(xy 495.91976 -124.3203) (xy 496.42776 -124.3203) (xy 496.42776 -124.7013) (xy 495.91976 -124.7013)
				)
			)
		)
	)
	(footprint ""
		(layer "B.Cu")
		(at 87.158068 -149.8092 -90)
		(property "Reference" "C5G99"
			(at -1.14681 0.76708 0)
			(unlocked yes)
			(layer "B.SilkS")
			(effects
				(font
					(size 0.7874 0.5842)
					(thickness 0.1524)
				)
				(justify mirror)
			)
		)
		(property "Value" ""
			(at 0 0 90)
			(layer "B.Fab")
			(effects
				(font
					(size 1.27 1.27)
				)
				(justify mirror)
			)
		)
		(duplicate_pad_numbers_are_jumpers no)
		(fp_rect
			(start 0.4953 1.6002)
			(end -0.4953 -0.2032)
			(stroke
				(width 0)
				(type default)
			)
			(fill no)
			(layer "B.CrtYd")
		)
		(fp_line
			(start -0.4953 1.6002)
			(end 0.4953 1.6002)
			(stroke
				(width 0.1)
				(type default)
			)
			(layer "B.Fab")
		)
		(fp_line
			(start 0.4953 1.6002)
			(end 0.4953 -0.2032)
			(stroke
				(width 0.1)
				(type default)
			)
			(layer "B.Fab")
		)
		(fp_line
			(start -0.4953 -0.2032)
			(end -0.4953 1.6002)
			(stroke
				(width 0.1)
				(type default)
			)
			(layer "B.Fab")
		)
		(fp_line
			(start 0.4953 -0.2032)
			(end -0.4953 -0.2032)
			(stroke
				(width 0.1)
				(type default)
			)
			(layer "B.Fab")
		)
		(pad "1" smd rect
			(at 0 0 90)
			(size 0.762 0.889)
			(layers "B.Cu" "B.Mask" "B.Paste")
			(net "PVDDQ_KLM")
		)
		(pad "2" smd rect
			(at 0 1.397 90)
			(size 0.762 0.889)
			(layers "B.Cu" "B.Mask" "B.Paste")
			(net "GND")
		)
		(zone
			(layer "B.Cu")
			(hatch none 0.5)
			(connect_pads
				(clearance 0)
			)
			(min_thickness 0.25)
			(keepout
				(tracks not_allowed)
				(vias allowed)
				(pads allowed)
				(copperpour not_allowed)
				(footprints allowed)
			)
			(placement
				(enabled no)
				(sheetname "")
			)
			(fill
				(thermal_gap 0.5)
				(thermal_bridge_width 0.5)
				(island_removal_mode 0)
			)
			(polygon
				(pts
					(xy 86.205568 -149.4282) (xy 86.713568 -149.4282) (xy 86.713568 -150.1902) (xy 86.205568 -150.1902)
				)
			)
		)
	)
	(footprint ""
		(layer "B.Cu")
		(at 362.671614 -124.440442 -90)
		(property "Reference" "C3M32"
			(at 0 0 90)
			(layer "B.SilkS")
			(hide yes)
			(effects
				(font
					(size 1.27 1.27)
				)
				(justify mirror)
			)
		)
		(property "Value" ""
			(at 0 0 90)
			(layer "B.Fab")
			(effects
				(font
					(size 1.27 1.27)
				)
				(justify mirror)
			)
		)
		(duplicate_pad_numbers_are_jumpers no)
		(fp_poly
			(pts
				(xy -0.3048 -0.1016) (xy -0.3048 0.9906) (xy 0.3048 0.9906) (xy 0.3048 -0.1016)
			)
			(stroke
				(width 0)
				(type default)
			)
			(fill no)
			(layer "B.CrtYd")
		)
		(fp_line
			(start -0.3048 0.9906)
			(end -0.3048 -0.1016)
			(stroke
				(width 0.1)
				(type default)
			)
			(layer "B.Fab")
		)
		(fp_line
			(start 0.3048 0.9906)
			(end -0.3048 0.9906)
			(stroke
				(width 0.1)
				(type default)
			)
			(layer "B.Fab")
		)
		(fp_line
			(start -0.3048 -0.1016)
			(end 0.3048 -0.1016)
			(stroke
				(width 0.1)
				(type default)
			)
			(layer "B.Fab")
		)
		(fp_line
			(start 0.3048 -0.1016)
			(end 0.3048 0.9906)
			(stroke
				(width 0.1)
				(type default)
			)
			(layer "B.Fab")
		)
		(pad "1" smd rect
			(at 0 0 90)
			(size 0.508 0.508)
			(layers "B.Cu" "B.Mask" "B.Paste")
			(net "P3E_CPU0_PE1_PCH_R_RXN<10>")
		)
		(pad "2" smd rect
			(at 0 0.889 90)
			(size 0.508 0.508)
			(layers "B.Cu" "B.Mask" "B.Paste")
			(net "P3E_CPU0_PE1_PCH_RXN<10>")
		)
		(zone
			(layer "B.Cu")
			(hatch none 0.5)
			(connect_pads
				(clearance 0)
			)
			(min_thickness 0.25)
			(keepout
				(tracks not_allowed)
				(vias allowed)
				(pads allowed)
				(copperpour not_allowed)
				(footprints allowed)
			)
			(placement
				(enabled no)
				(sheetname "")
			)
			(fill
				(thermal_gap 0.5)
				(thermal_bridge_width 0.5)
				(island_removal_mode 0)
			)
			(polygon
				(pts
					(xy 362.036614 -124.186442) (xy 362.036614 -124.694442) (xy 362.417614 -124.694442) (xy 362.417614 -124.186442)
				)
			)
		)
		(zone
			(layer "B.Cu")
			(hatch none 0.5)
			(connect_pads
				(clearance 0)
			)
			(min_thickness 0.25)
			(keepout
				(tracks allowed)
				(vias not_allowed)
				(pads allowed)
				(copperpour not_allowed)
				(footprints allowed)
			)
			(placement
				(enabled no)
				(sheetname "")
			)
			(fill
				(thermal_gap 0.5)
				(thermal_bridge_width 0.5)
				(island_removal_mode 0)
			)
			(polygon
				(pts
					(xy 362.417614 -124.186442) (xy 362.417614 -124.694442) (xy 362.036614 -124.694442) (xy 362.036614 -124.186442)
				)
			)
		)
	)
)
